(kicad_pcb
	(version 20260206)
	(generator "pcbnew")
	(generator_version "10.0")
	(general
		(thickness 1.6)
		(legacy_teardrops no)
	)
	(paper "A4")
	(title_block
		(title "03242023_DA0F0TMBIJ0_F0T_Motherboard_J_brd_V01_OCP.brd")
		(comment 1 "Grand Teton / footprint 1682 of 6105 (U1), pads 2918-3024 of 4677")
	)
	(layers
		(0 "F.Cu" signal "TOP")
		(4 "In1.Cu" signal "GND")
		(6 "In2.Cu" signal "IN1")
		(8 "In3.Cu" signal "GND1")
		(10 "In4.Cu" signal "IN2")
		(12 "In5.Cu" signal "GND2")
		(14 "In6.Cu" signal "IN3")
		(16 "In7.Cu" signal "GND3")
		(18 "In8.Cu" signal "VCC")
		(20 "In9.Cu" signal "VCC1")
		(22 "In10.Cu" signal "GND4")
		(24 "In11.Cu" signal "IN4")
		(26 "In12.Cu" signal "GND5")
		(28 "In13.Cu" signal "IN5")
		(30 "In14.Cu" signal "GND6")
		(32 "In15.Cu" signal "IN6")
		(34 "In16.Cu" signal "GND7")
		(2 "B.Cu" signal "BOTTOM")
		(9 "F.Adhes" user "F.Adhesive")
		(11 "B.Adhes" user "B.Adhesive")
		(13 "F.Paste" user "Package Geometry/Pastemask Top")
		(15 "B.Paste" user "Package Geometry/Pastemask Bottom")
		(5 "F.SilkS" user "Ref Des/Silkscreen Top")
		(7 "B.SilkS" user "Ref Des/Silkscreen Bottom")
		(1 "F.Mask" user "Board Geometry/Soldermask Top")
		(3 "B.Mask" user "Board Geometry/Soldermask Bottom")
		(17 "Dwgs.User" user "User.Drawings")
		(19 "Cmts.User" user "User.Comments")
		(21 "Eco1.User" user "User.Eco1")
		(23 "Eco2.User" user "User.Eco2")
		(25 "Edge.Cuts" user "Board Geometry/Outline")
		(27 "Margin" user)
		(31 "F.CrtYd" user "Package Geometry/Place Bound Top")
		(29 "B.CrtYd" user "Package Geometry/Place Bound Bottom")
		(35 "F.Fab" user "Ref Des/Assembly Top")
		(33 "B.Fab" user "Ref Des/Assembly Bottom")
	)
	(footprint ""
		(layer "F.Cu")
		(at 111.93018 -251.76988 90)
		(property "Reference" "U1"
			(at -74.913236 41.548812 0)
			(unlocked yes)
			(layer "F.SilkS")
			(effects
				(font
					(size 1.6002 1.1938)
					(thickness 0.1524)
				)
				(justify left)
			)
		)
		(property "Value" ""
			(at 0 0 90)
			(layer "F.Fab")
			(effects
				(font
					(size 1.27 1.27)
				)
			)
		)
		(duplicate_pad_numbers_are_jumpers no)
		(pad "DM67" smd circle
			(at 17.89176 15.796514 270)
			(size 0.4318 0.4318)
			(layers "F.Cu" "F.Mask" "F.Paste")
			(net "GND")
		)
		(pad "DM69" smd circle
			(at 19.519392 15.796514 270)
			(size 0.4318 0.4318)
			(layers "F.Cu" "F.Mask" "F.Paste")
			(net "GND")
		)
		(pad "DM71" smd circle
			(at 21.147278 15.796514 270)
			(size 0.4318 0.4318)
			(layers "F.Cu" "F.Mask" "F.Paste")
			(net "GND")
		)
		(pad "DM73" smd circle
			(at 22.77491 15.796514 270)
			(size 0.4318 0.4318)
			(layers "F.Cu" "F.Mask" "F.Paste")
			(net "GND")
		)
		(pad "DM75" smd circle
			(at 24.402796 15.796514 270)
			(size 0.4318 0.4318)
			(layers "F.Cu" "F.Mask" "F.Paste")
			(net "GND")
		)
		(pad "DM77" smd circle
			(at 26.030682 15.796514 270)
			(size 0.4318 0.4318)
			(layers "F.Cu" "F.Mask" "F.Paste")
			(net "GND")
		)
		(pad "DM79" smd circle
			(at 27.658314 15.796514 270)
			(size 0.4318 0.4318)
			(layers "F.Cu" "F.Mask" "F.Paste")
			(net "GND")
		)
		(pad "DM81" smd circle
			(at 29.2862 15.796514 270)
			(size 0.4318 0.4318)
			(layers "F.Cu" "F.Mask" "F.Paste")
			(net "Net_747")
		)
		(pad "DM83" smd circle
			(at 30.914086 15.796514 270)
			(size 0.4318 0.4318)
			(layers "F.Cu" "F.Mask" "F.Paste")
			(net "PVCCFA_EHV_FIVRA_CPU1")
		)
		(pad "DM85" smd circle
			(at 32.541718 15.796514 270)
			(size 0.4318 0.4318)
			(layers "F.Cu" "F.Mask" "F.Paste")
			(net "PVCCFA_EHV_FIVRA_CPU1")
		)
		(pad "DM87" smd circle
			(at 34.169604 15.796514 270)
			(size 0.4318 0.4318)
			(layers "F.Cu" "F.Mask" "F.Paste")
			(net "P5E_CPU1_PE3_TX_DN<6>")
		)
		(pad "DM89" smd circle
			(at 35.797236 15.796514 270)
			(size 0.4318 0.4318)
			(layers "F.Cu" "F.Mask" "F.Paste")
			(net "PVCCFA_EHV_FIVRA_CPU1")
		)
		(pad "DM91" smd oval
			(at 37.425122 15.796514)
			(size 0.381 0.4826)
			(drill
				(offset 0 -0.0508)
			)
			(layers "F.Cu" "F.Mask" "F.Paste")
			(net "P5E_CPU1_PE3_RX_DP<7>")
		)
		(pad "DN1" smd oval
			(at -37.425122 16.156686 180)
			(size 0.381 0.4826)
			(drill
				(offset 0 -0.0508)
			)
			(layers "F.Cu" "F.Mask" "F.Paste")
			(net "UPI_CPU0_CPU1_P0P1_DN<7>")
		)
		(pad "DN3" smd circle
			(at -35.797236 16.156686 270)
			(size 0.4318 0.4318)
			(layers "F.Cu" "F.Mask" "F.Paste")
			(net "PVCCFA_EHV_FIVRA_CPU1")
		)
		(pad "DN5" smd circle
			(at -34.169604 16.156686 270)
			(size 0.4318 0.4318)
			(layers "F.Cu" "F.Mask" "F.Paste")
			(net "UPI_CPU1_CPU0_P1P0_DP<6>")
		)
		(pad "DN7" smd circle
			(at -32.541718 16.156686 270)
			(size 0.4318 0.4318)
			(layers "F.Cu" "F.Mask" "F.Paste")
			(net "PVCCFA_EHV_FIVRA_CPU1")
		)
		(pad "DN9" smd circle
			(at -30.914086 16.156686 270)
			(size 0.4318 0.4318)
			(layers "F.Cu" "F.Mask" "F.Paste")
			(net "P5E_CPU1_PE2_RX_DN<8>")
		)
		(pad "DN11" smd circle
			(at -29.2862 16.156686 270)
			(size 0.4318 0.4318)
			(layers "F.Cu" "F.Mask" "F.Paste")
			(net "PVCCFA_EHV_FIVRA_CPU1")
		)
		(pad "DN13" smd circle
			(at -27.658314 16.156686 270)
			(size 0.4318 0.4318)
			(layers "F.Cu" "F.Mask" "F.Paste")
			(net "P5E_CPU1_PE2_TX_DN<8>")
		)
		(pad "DN15" smd circle
			(at -26.030682 16.156686 270)
			(size 0.4318 0.4318)
			(layers "F.Cu" "F.Mask" "F.Paste")
			(net "PVCCFA_EHV_FIVRA_CPU1")
		)
		(pad "DN17" smd circle
			(at -24.402796 16.156686 270)
			(size 0.4318 0.4318)
			(layers "F.Cu" "F.Mask" "F.Paste")
			(net "GND")
		)
		(pad "DN19" smd circle
			(at -22.77491 16.156686 270)
			(size 0.4318 0.4318)
			(layers "F.Cu" "F.Mask" "F.Paste")
			(net "M_H_CPU1_SB_DQ<23>")
		)
		(pad "DN21" smd circle
			(at -21.147278 16.156686 270)
			(size 0.4318 0.4318)
			(layers "F.Cu" "F.Mask" "F.Paste")
			(net "M_H_CPU1_SB_DQS_DP<7>")
		)
		(pad "DN23" smd circle
			(at -19.519392 16.156686 270)
			(size 0.4318 0.4318)
			(layers "F.Cu" "F.Mask" "F.Paste")
			(net "M_H_CPU1_SB_DQ<18>")
		)
		(pad "DN25" smd circle
			(at -17.89176 16.156686 270)
			(size 0.4318 0.4318)
			(layers "F.Cu" "F.Mask" "F.Paste")
			(net "M_G_CPU1_SB_DQ<15>")
		)
		(pad "DN27" smd circle
			(at -16.263874 16.156686 270)
			(size 0.4318 0.4318)
			(layers "F.Cu" "F.Mask" "F.Paste")
			(net "M_G_CPU1_SB_DQS_DN<6>")
		)
		(pad "DN29" smd circle
			(at -14.635988 16.156686 270)
			(size 0.4318 0.4318)
			(layers "F.Cu" "F.Mask" "F.Paste")
			(net "M_G_CPU1_SB_DQ<8>")
		)
		(pad "DN31" smd circle
			(at -13.008356 16.156686 270)
			(size 0.4318 0.4318)
			(layers "F.Cu" "F.Mask" "F.Paste")
			(net "M_G_CPU1_SB_DQ<7>")
		)
		(pad "DN33" smd circle
			(at -11.380724 16.156686 270)
			(size 0.4318 0.4318)
			(layers "F.Cu" "F.Mask" "F.Paste")
			(net "M_G_CPU1_SB_DQS_DP<5>")
		)
		(pad "DN35" smd circle
			(at -9.752838 16.156686 270)
			(size 0.4318 0.4318)
			(layers "F.Cu" "F.Mask" "F.Paste")
			(net "M_G_CPU1_SB_DQ<2>")
		)
		(pad "DN37" smd circle
			(at -8.124952 16.156686 270)
			(size 0.4318 0.4318)
			(layers "F.Cu" "F.Mask" "F.Paste")
			(net "M_H_CPU1_SB_CS_N<1>")
		)
		(pad "DN39" smd circle
			(at -6.49732 16.156686 270)
			(size 0.4318 0.4318)
			(layers "F.Cu" "F.Mask" "F.Paste")
			(net "GND")
		)
		(pad "DN41" smd circle
			(at -4.869434 16.156686 270)
			(size 0.4318 0.4318)
			(layers "F.Cu" "F.Mask" "F.Paste")
			(net "M_H_CPU1_SB_CA<3>")
		)
		(pad "DN43" smd circle
			(at -3.241802 16.156686 270)
			(size 0.4318 0.4318)
			(layers "F.Cu" "F.Mask" "F.Paste")
			(net "M_G_CPU1_SB_CA<0>")
		)
		(pad "DN45" smd circle
			(at -1.613916 16.156686 270)
			(size 0.4318 0.4318)
			(layers "F.Cu" "F.Mask" "F.Paste")
			(net "M_G_CPU1_CLK_DP<0>")
		)
		(pad "DN48" smd circle
			(at 2.427732 16.266668 270)
			(size 0.4318 0.4318)
			(layers "F.Cu" "F.Mask" "F.Paste")
			(net "M_F_CPU1_SA_RSP<0>")
		)
		(pad "DN50" smd circle
			(at 4.055618 16.266668 270)
			(size 0.4318 0.4318)
			(layers "F.Cu" "F.Mask" "F.Paste")
			(net "M_G_CPU1_SA_CA<5>")
		)
		(pad "DN52" smd circle
			(at 5.68325 16.266668 270)
			(size 0.4318 0.4318)
			(layers "F.Cu" "F.Mask" "F.Paste")
			(net "GND")
		)
		(pad "DN54" smd circle
			(at 7.311136 16.266668 270)
			(size 0.4318 0.4318)
			(layers "F.Cu" "F.Mask" "F.Paste")
			(net "M_G_CPU1_SA_CS_N<0>")
		)
		(pad "DN56" smd circle
			(at 8.939022 16.266668 270)
			(size 0.4318 0.4318)
			(layers "F.Cu" "F.Mask" "F.Paste")
			(net "M_G_CPU1_SA_CB<7>")
		)
		(pad "DN58" smd circle
			(at 10.566654 16.266668 270)
			(size 0.4318 0.4318)
			(layers "F.Cu" "F.Mask" "F.Paste")
			(net "M_G_CPU1_SA_DQS_DP<9>")
		)
		(pad "DN60" smd circle
			(at 12.19454 16.266668 270)
			(size 0.4318 0.4318)
			(layers "F.Cu" "F.Mask" "F.Paste")
			(net "M_G_CPU1_SA_CB<2>")
		)
		(pad "DN62" smd circle
			(at 13.822426 16.266668 270)
			(size 0.4318 0.4318)
			(layers "F.Cu" "F.Mask" "F.Paste")
			(net "M_G_CPU1_SA_DQ<31>")
		)
		(pad "DN64" smd circle
			(at 15.450058 16.266668 270)
			(size 0.4318 0.4318)
			(layers "F.Cu" "F.Mask" "F.Paste")
			(net "M_G_CPU1_SA_DQS_DP<8>")
		)
		(pad "DN66" smd circle
			(at 17.07769 16.266668 270)
			(size 0.4318 0.4318)
			(layers "F.Cu" "F.Mask" "F.Paste")
			(net "M_G_CPU1_SA_DQ<26>")
		)
		(pad "DN68" smd circle
			(at 18.705576 16.266668 270)
			(size 0.4318 0.4318)
			(layers "F.Cu" "F.Mask" "F.Paste")
			(net "M_G_CPU1_SA_DQ<15>")
		)
		(pad "DN70" smd circle
			(at 20.333462 16.266668 270)
			(size 0.4318 0.4318)
			(layers "F.Cu" "F.Mask" "F.Paste")
			(net "M_G_CPU1_SA_DQS_DP<6>")
		)
		(pad "DN72" smd circle
			(at 21.961094 16.266668 270)
			(size 0.4318 0.4318)
			(layers "F.Cu" "F.Mask" "F.Paste")
			(net "M_G_CPU1_SA_DQ<10>")
		)
		(pad "DN74" smd circle
			(at 23.58898 16.266668 270)
			(size 0.4318 0.4318)
			(layers "F.Cu" "F.Mask" "F.Paste")
			(net "M_H_CPU1_SA_DQ<7>")
		)
		(pad "DN76" smd circle
			(at 25.216612 16.266668 270)
			(size 0.4318 0.4318)
			(layers "F.Cu" "F.Mask" "F.Paste")
			(net "M_H_CPU1_SA_DQS_DP<5>")
		)
		(pad "DN78" smd circle
			(at 26.844498 16.266668 270)
			(size 0.4318 0.4318)
			(layers "F.Cu" "F.Mask" "F.Paste")
			(net "GND")
		)
		(pad "DN80" smd circle
			(at 28.472384 16.266668 270)
			(size 0.4318 0.4318)
			(layers "F.Cu" "F.Mask" "F.Paste")
			(net "Net_722")
		)
		(pad "DN82" smd circle
			(at 30.100016 16.266668 270)
			(size 0.4318 0.4318)
			(layers "F.Cu" "F.Mask" "F.Paste")
			(net "Net_726")
		)
		(pad "DN84" smd circle
			(at 31.727902 16.266668 270)
			(size 0.4318 0.4318)
			(layers "F.Cu" "F.Mask" "F.Paste")
			(net "GND")
		)
		(pad "DN86" smd circle
			(at 33.355534 16.266668 270)
			(size 0.4318 0.4318)
			(layers "F.Cu" "F.Mask" "F.Paste")
			(net "P5E_CPU1_PE3_TX_DP<6>")
		)
		(pad "DN88" smd circle
			(at 34.98342 16.266668 270)
			(size 0.4318 0.4318)
			(layers "F.Cu" "F.Mask" "F.Paste")
			(net "GND")
		)
		(pad "DN90" smd circle
			(at 36.611306 16.266668 270)
			(size 0.4318 0.4318)
			(layers "F.Cu" "F.Mask" "F.Paste")
			(net "P5E_CPU1_PE3_RX_DN<7>")
		)
		(pad "DP2" smd circle
			(at -36.611306 16.626332 270)
			(size 0.4318 0.4318)
			(layers "F.Cu" "F.Mask" "F.Paste")
			(net "UPI_CPU0_CPU1_P0P1_DP<7>")
		)
		(pad "DP4" smd circle
			(at -34.98342 16.626332 270)
			(size 0.4318 0.4318)
			(layers "F.Cu" "F.Mask" "F.Paste")
			(net "GND")
		)
		(pad "DP6" smd circle
			(at -33.355534 16.626332 270)
			(size 0.4318 0.4318)
			(layers "F.Cu" "F.Mask" "F.Paste")
			(net "UPI_CPU1_CPU0_P1P0_DN<6>")
		)
		(pad "DP8" smd circle
			(at -31.727902 16.626332 270)
			(size 0.4318 0.4318)
			(layers "F.Cu" "F.Mask" "F.Paste")
			(net "GND")
		)
		(pad "DP10" smd circle
			(at -30.100016 16.626332 270)
			(size 0.4318 0.4318)
			(layers "F.Cu" "F.Mask" "F.Paste")
			(net "P5E_CPU1_PE2_RX_DP<8>")
		)
		(pad "DP12" smd circle
			(at -28.472384 16.626332 270)
			(size 0.4318 0.4318)
			(layers "F.Cu" "F.Mask" "F.Paste")
			(net "GND")
		)
		(pad "DP14" smd circle
			(at -26.844498 16.626332 270)
			(size 0.4318 0.4318)
			(layers "F.Cu" "F.Mask" "F.Paste")
			(net "P5E_CPU1_PE2_TX_DN<9>")
		)
		(pad "DP16" smd circle
			(at -25.216612 16.626332 270)
			(size 0.4318 0.4318)
			(layers "F.Cu" "F.Mask" "F.Paste")
			(net "GND")
		)
		(pad "DP18" smd circle
			(at -23.58898 16.626332 270)
			(size 0.4318 0.4318)
			(layers "F.Cu" "F.Mask" "F.Paste")
			(net "GND")
		)
		(pad "DP20" smd circle
			(at -21.961094 16.626332 270)
			(size 0.4318 0.4318)
			(layers "F.Cu" "F.Mask" "F.Paste")
			(net "M_H_CPU1_SB_DQ<22>")
		)
		(pad "DP22" smd circle
			(at -20.333462 16.626332 270)
			(size 0.4318 0.4318)
			(layers "F.Cu" "F.Mask" "F.Paste")
			(net "M_H_CPU1_SB_DQ<19>")
		)
		(pad "DP24" smd circle
			(at -18.705576 16.626332 270)
			(size 0.4318 0.4318)
			(layers "F.Cu" "F.Mask" "F.Paste")
			(net "GND")
		)
		(pad "DP26" smd circle
			(at -17.07769 16.626332 270)
			(size 0.4318 0.4318)
			(layers "F.Cu" "F.Mask" "F.Paste")
			(net "M_G_CPU1_SB_DQ<14>")
		)
		(pad "DP28" smd circle
			(at -15.450058 16.626332 270)
			(size 0.4318 0.4318)
			(layers "F.Cu" "F.Mask" "F.Paste")
			(net "M_G_CPU1_SB_DQ<11>")
		)
		(pad "DP30" smd circle
			(at -13.822426 16.626332 270)
			(size 0.4318 0.4318)
			(layers "F.Cu" "F.Mask" "F.Paste")
			(net "GND")
		)
		(pad "DP32" smd circle
			(at -12.19454 16.626332 270)
			(size 0.4318 0.4318)
			(layers "F.Cu" "F.Mask" "F.Paste")
			(net "M_G_CPU1_SB_DQ<6>")
		)
		(pad "DP34" smd circle
			(at -10.566654 16.626332 270)
			(size 0.4318 0.4318)
			(layers "F.Cu" "F.Mask" "F.Paste")
			(net "M_G_CPU1_SB_DQ<3>")
		)
		(pad "DP36" smd circle
			(at -8.939022 16.626332 270)
			(size 0.4318 0.4318)
			(layers "F.Cu" "F.Mask" "F.Paste")
			(net "GND")
		)
		(pad "DP38" smd circle
			(at -7.311136 16.626332 270)
			(size 0.4318 0.4318)
			(layers "F.Cu" "F.Mask" "F.Paste")
			(net "M_H_CPU1_SB_CS_N<3>")
		)
		(pad "DP40" smd circle
			(at -5.68325 16.626332 270)
			(size 0.4318 0.4318)
			(layers "F.Cu" "F.Mask" "F.Paste")
			(net "M_H_CPU1_SB_CA<5>")
		)
		(pad "DP42" smd circle
			(at -4.055618 16.626332 270)
			(size 0.4318 0.4318)
			(layers "F.Cu" "F.Mask" "F.Paste")
			(net "GND")
		)
		(pad "DP44" smd circle
			(at -2.427732 16.626332 270)
			(size 0.4318 0.4318)
			(layers "F.Cu" "F.Mask" "F.Paste")
			(net "M_G_CPU1_SB_CA<1>")
		)
		(pad "DP47" smd circle
			(at 1.613916 16.736314 270)
			(size 0.4318 0.4318)
			(layers "F.Cu" "F.Mask" "F.Paste")
			(net "M_F_CPU1_SA_RSP<1>")
		)
		(pad "DP49" smd circle
			(at 3.241802 16.736314 270)
			(size 0.4318 0.4318)
			(layers "F.Cu" "F.Mask" "F.Paste")
			(net "GND")
		)
		(pad "DP51" smd circle
			(at 4.869434 16.736314 270)
			(size 0.4318 0.4318)
			(layers "F.Cu" "F.Mask" "F.Paste")
			(net "M_G_CPU1_SA_CA<3>")
		)
		(pad "DP53" smd circle
			(at 6.49732 16.736314 270)
			(size 0.4318 0.4318)
			(layers "F.Cu" "F.Mask" "F.Paste")
			(net "M_G_CPU1_SA_CS_N<1>")
		)
		(pad "DP55" smd circle
			(at 8.124952 16.736314 270)
			(size 0.4318 0.4318)
			(layers "F.Cu" "F.Mask" "F.Paste")
			(net "GND")
		)
		(pad "DP57" smd circle
			(at 9.752838 16.736314 270)
			(size 0.4318 0.4318)
			(layers "F.Cu" "F.Mask" "F.Paste")
			(net "M_G_CPU1_SA_CB<6>")
		)
		(pad "DP59" smd circle
			(at 11.380724 16.736314 270)
			(size 0.4318 0.4318)
			(layers "F.Cu" "F.Mask" "F.Paste")
			(net "M_G_CPU1_SA_CB<3>")
		)
		(pad "DP61" smd circle
			(at 13.008356 16.736314 270)
			(size 0.4318 0.4318)
			(layers "F.Cu" "F.Mask" "F.Paste")
			(net "GND")
		)
		(pad "DP63" smd circle
			(at 14.635988 16.736314 270)
			(size 0.4318 0.4318)
			(layers "F.Cu" "F.Mask" "F.Paste")
			(net "M_G_CPU1_SA_DQ<30>")
		)
		(pad "DP65" smd circle
			(at 16.263874 16.736314 270)
			(size 0.4318 0.4318)
			(layers "F.Cu" "F.Mask" "F.Paste")
			(net "M_G_CPU1_SA_DQ<27>")
		)
		(pad "DP67" smd circle
			(at 17.89176 16.736314 270)
			(size 0.4318 0.4318)
			(layers "F.Cu" "F.Mask" "F.Paste")
			(net "GND")
		)
		(pad "DP69" smd circle
			(at 19.519392 16.736314 270)
			(size 0.4318 0.4318)
			(layers "F.Cu" "F.Mask" "F.Paste")
			(net "M_G_CPU1_SA_DQ<14>")
		)
		(pad "DP71" smd circle
			(at 21.147278 16.736314 270)
			(size 0.4318 0.4318)
			(layers "F.Cu" "F.Mask" "F.Paste")
			(net "M_G_CPU1_SA_DQ<11>")
		)
		(pad "DP73" smd circle
			(at 22.77491 16.736314 270)
			(size 0.4318 0.4318)
			(layers "F.Cu" "F.Mask" "F.Paste")
			(net "GND")
		)
		(pad "DP75" smd circle
			(at 24.402796 16.736314 270)
			(size 0.4318 0.4318)
			(layers "F.Cu" "F.Mask" "F.Paste")
			(net "M_H_CPU1_SA_DQ<6>")
		)
		(pad "DP77" smd circle
			(at 26.030682 16.736314 270)
			(size 0.4318 0.4318)
			(layers "F.Cu" "F.Mask" "F.Paste")
			(net "M_H_CPU1_SA_DQ<3>")
		)
		(pad "DP79" smd circle
			(at 27.658314 16.736314 270)
			(size 0.4318 0.4318)
			(layers "F.Cu" "F.Mask" "F.Paste")
			(net "Net_727")
		)
		(pad "DP81" smd circle
			(at 29.2862 16.736314 270)
			(size 0.4318 0.4318)
			(layers "F.Cu" "F.Mask" "F.Paste")
			(net "GND")
		)
		(pad "DP83" smd circle
			(at 30.914086 16.736314 270)
			(size 0.4318 0.4318)
			(layers "F.Cu" "F.Mask" "F.Paste")
			(net "Net_702")
		)
		(pad "DP85" smd circle
			(at 32.541718 16.736314 270)
			(size 0.4318 0.4318)
			(layers "F.Cu" "F.Mask" "F.Paste")
			(net "P5E_CPU1_PE3_TX_DN<5>")
		)
		(pad "DP87" smd circle
			(at 34.169604 16.736314 270)
			(size 0.4318 0.4318)
			(layers "F.Cu" "F.Mask" "F.Paste")
			(net "GND")
		)
		(pad "DP89" smd circle
			(at 35.797236 16.736314 270)
			(size 0.4318 0.4318)
			(layers "F.Cu" "F.Mask" "F.Paste")
			(net "P5E_CPU1_PE3_RX_DN<6>")
		)
		(pad "DP91" smd oval
			(at 37.425122 16.736314)
			(size 0.381 0.4826)
			(drill
				(offset 0 -0.0508)
			)
			(layers "F.Cu" "F.Mask" "F.Paste")
			(net "GND")
		)
		(pad "DR1" smd oval
			(at -37.425122 17.096486 180)
			(size 0.381 0.4826)
			(drill
				(offset 0 -0.0508)
			)
			(layers "F.Cu" "F.Mask" "F.Paste")
			(net "GND")
		)
		(pad "DR3" smd circle
			(at -35.797236 17.096486 270)
			(size 0.4318 0.4318)
			(layers "F.Cu" "F.Mask" "F.Paste")
			(net "UPI_CPU0_CPU1_P0P1_DP<6>")
		)
		(pad "DR5" smd circle
			(at -34.169604 17.096486 270)
			(size 0.4318 0.4318)
			(layers "F.Cu" "F.Mask" "F.Paste")
			(net "GND")
		)
		(pad "DR7" smd circle
			(at -32.541718 17.096486 270)
			(size 0.4318 0.4318)
			(layers "F.Cu" "F.Mask" "F.Paste")
			(net "UPI_CPU1_CPU0_P1P0_DP<5>")
		)
	)
)
